# S9S_MB_2U (Grand Teton) — schematic netlist excerpt (pin names and nets, part order shuffled) for the footprints in the layout excerpt that follows; sources: Cadence DE-HDL packaged netlist, KiCad conversion of 03242023_DA0F0TMBIJ0_F0T_Motherboard_J_brd_V01_OCP.brd

J22  SCONN288_ADR50017P087CC  SCONN288_ADR50017-P087CC IO  pkg DDR288S_1-1VXB  page 103
  VIN_BULK0  = P12V_S3_AUX_CPU1_NVDIMM
  RFU0  = TP_CHC_CPU1_DIMM2_FRU_0
  VIN_MGMT  = P3V3_AUX
  HSCL  = I3C_SPD_DDRABCD_CPU1_LVC1_SCL_5
  HSDA  = I3C_SPD_DDRABCD_CPU1_LVC1_SDA
  VSS0  = GND
  DQ0_A  = M_C_CPU1_SA_DQ<0>
  VSS1  = GND
  DQ1_A  = M_C_CPU1_SA_DQ<1>
  VSS2  = GND
  DQS0_A_T  = M_C_CPU1_SA_DQS_DP<0>
  DQS0_A_C  = M_C_CPU1_SA_DQS_DN<0>
  VSS3  = GND
  DQ4_A  = M_C_CPU1_SA_DQ<4>
  VSS4  = GND
  DQ5_A  = M_C_CPU1_SA_DQ<5>
  VSS5  = GND
  DQ8_A  = M_C_CPU1_SA_DQ<8>
  VSS6  = GND
  DQ9_A  = M_C_CPU1_SA_DQ<9>
  VSS7  = GND
  DQS1_A_T  = M_C_CPU1_SA_DQS_DP<1>
  DQS1_A_C  = M_C_CPU1_SA_DQS_DN<1>
  VSS8  = GND
  DQ12_A  = M_C_CPU1_SA_DQ<12>
  VSS9  = GND
  DQ13_A  = M_C_CPU1_SA_DQ<13>
  VSS10  = GND
  DQ16_A  = M_C_CPU1_SA_DQ<16>
  VSS11  = GND
  DQ17_A  = M_C_CPU1_SA_DQ<17>
  VSS12  = GND
  DQS2_A_T  = M_C_CPU1_SA_DQS_DP<2>
  DQS2_A_C  = M_C_CPU1_SA_DQS_DN<2>
  VSS13  = GND
  DQ20_A  = M_C_CPU1_SA_DQ<20>
  VSS14  = GND
  DQ21_A  = M_C_CPU1_SA_DQ<21>
  VSS15  = GND
  DQ24_A  = M_C_CPU1_SA_DQ<24>
  VSS16  = GND
  DQ25_A  = M_C_CPU1_SA_DQ<25>
  VSS17  = GND
  DQS3_A_T  = M_C_CPU1_SA_DQS_DP<3>
  DQS3_A_C  = M_C_CPU1_SA_DQS_DN<3>
  VSS18  = GND
  DQ28_A  = M_C_CPU1_SA_DQ<28>
  VSS19  = GND
  DQ29_A  = M_C_CPU1_SA_DQ<29>
  VSS20  = GND
  CB0_A  = M_C_CPU1_SA_CB<0>
  VSS21  = GND
  CB1_A  = M_C_CPU1_SA_CB<1>
  VSS22  = GND
  DQS4_A_T  = M_C_CPU1_SA_DQS_DP<4>
  DQS4_A_C  = M_C_CPU1_SA_DQS_DN<4>
  VSS23  = GND
  CB4_A  = M_C_CPU1_SA_CB<4>
  VSS24  = GND
  CB5_A  = M_C_CPU1_SA_CB<5>
  VSS25  = GND
  ALERT_N  = M_C_CPU1_ALERT_N
  VSS26  = GND
  CS0_A_N  = M_C_CPU1_SA_CS_N<2>
  VSS27  = GND
  CA0_A  = M_C_CPU1_SA_CA<0>
  VSS28  = GND
  CA2_A  = M_C_CPU1_SA_CA<2>
  VSS29  = GND
  CA4_A  = M_C_CPU1_SA_CA<4>
  VSS30  = GND
  CA6_A  = M_C_CPU1_SA_CA<6>
  VSS31  = GND
  PAR_A  = M_C_CPU1_SA_PAR
  VSS32  = GND
  CA0_B  = M_C_CPU1_SB_CA<0>
  VSS33  = GND
  CA2_B  = M_C_CPU1_SB_CA<2>
  VSS34  = GND
  CA4_B  = M_C_CPU1_SB_CA<4>
  VSS35  = GND
  CA6_B  = M_C_CPU1_SB_CA<6>
  VSS36  = GND
  CS0_B_N  = M_C_CPU1_SB_CS_N<2>
  VSS37  = GND
  \lbd||rsp_a_n\  = M_C_CPU1_SA_RSP<1>
  \lbs||rsp_b_n\  = M_C_CPU1_SB_RSP<1>
  VSS38  = GND
  CB4_B  = M_C_CPU1_SB_CB<4>
  VSS39  = GND
  CB5_B  = M_C_CPU1_SB_CB<5>
  VSS40  = GND
  \dqs9_b_t||tdqs9_b_t||dbi4_b_n\  = M_C_CPU1_SB_DQS_DP<9>
  \dqs9_b_c||tdqs9_b_c\  = M_C_CPU1_SB_DQS_DN<9>
  VSS41  = GND
  CB0_B  = M_C_CPU1_SB_CB<0>
  VSS42  = GND
  CB1_B  = M_C_CPU1_SB_CB<1>
  VSS43  = GND
  DQ0_B  = M_C_CPU1_SB_DQ<0>
  VSS44  = GND
  DQ1_B  = M_C_CPU1_SB_DQ<1>
  VSS45  = GND
  DQS0_B_T  = M_C_CPU1_SB_DQS_DP<0>
  DQS0_B_C  = M_C_CPU1_SB_DQS_DN<0>
  VSS46  = GND
  DQ4_B  = M_C_CPU1_SB_DQ<4>
  VSS47  = GND
  DQ5_B  = M_C_CPU1_SB_DQ<5>
  VSS48  = GND
  DQ8_B  = M_C_CPU1_SB_DQ<8>
  VSS49  = GND
  DQ9_B  = M_C_CPU1_SB_DQ<9>
  VSS50  = GND
  DQS1_B_T  = M_C_CPU1_SB_DQS_DP<1>
  DQS1_B_C  = M_C_CPU1_SB_DQS_DN<1>
  VSS51  = GND
  DQ12_B  = M_C_CPU1_SB_DQ<12>
  VSS52  = GND
  DQ13_B  = M_C_CPU1_SB_DQ<13>
  VSS53  = GND
  DQ16_B  = M_C_CPU1_SB_DQ<16>
  VSS54  = GND
  DQ17_B  = M_C_CPU1_SB_DQ<17>
  VSS55  = GND
  DQS2_B_T  = M_C_CPU1_SB_DQS_DP<2>
  DQS2_B_C  = M_C_CPU1_SB_DQS_DN<2>
  VSS56  = GND
  DQ20_B  = M_C_CPU1_SB_DQ<20>
  VSS57  = GND
  DQ21_B  = M_C_CPU1_SB_DQ<21>
  VSS58  = GND
  DQ24_B  = M_C_CPU1_SB_DQ<24>
  VSS59  = GND
  DQ25_B  = M_C_CPU1_SB_DQ<25>
  VSS60  = GND
  DQS3_B_T  = M_C_CPU1_SB_DQS_DP<3>
  DQS3_B_C  = M_C_CPU1_SB_DQS_DN<3>
  VSS61  = GND
  DQ28_B  = M_C_CPU1_SB_DQ<28>
  VSS62  = GND
  DQ29_B  = M_C_CPU1_SB_DQ<29>
  VSS63  = GND
  RFU1  = TP_CHC_CPU1_DIMM2_FRU_1
  VIN_BULK1  = P12V_S3_AUX_CPU1_NVDIMM
  VIN_BULK2  = P12V_S3_AUX_CPU1_NVDIMM
  \pwr_good||fail_n\  = PWRGD_CHC_CPU1_DIMM2
  HSA  = PD_CHC_CPU1_DIMM2_SAA
  RFU2  = TP_CHC_CPU1_DIMM2_FRU_2
  RFU3  = TP_CHC_CPU1_DIMM2_FRU_3
  VSS64  = GND
  DQ2_A  = M_C_CPU1_SA_DQ<2>
  VSS65  = GND
  DQ3_A  = M_C_CPU1_SA_DQ<3>
  VSS66  = GND
  \dqs5_a_c||tdqs5_a_c||dqs5_a_t||tdqs5_a_t\  = M_C_CPU1_SA_DQS_DN<5>
  \dqs5_a_t||tdqs5_a_t\  = M_C_CPU1_SA_DQS_DP<5>
  VSS67  = GND
  DQ6_A  = M_C_CPU1_SA_DQ<6>
  VSS68  = GND
  DQ7_A  = M_C_CPU1_SA_DQ<7>
  VSS69  = GND
  DQ10_A  = M_C_CPU1_SA_DQ<10>
  VSS70  = GND
  DQ11_A  = M_C_CPU1_SA_DQ<11>
  VSS71  = GND
  \dqs6_a_c||tdqs6_a_c||dqs6_a_t||tdqs6_a_t\  = M_C_CPU1_SA_DQS_DN<6>
  \dqs6_a_t||tdqs6_a_t\  = M_C_CPU1_SA_DQS_DP<6>
  VSS72  = GND
  DQ14_A  = M_C_CPU1_SA_DQ<14>
  VSS73  = GND
  DQ15_A  = M_C_CPU1_SA_DQ<15>
  VSS74  = GND
  DQ18_A  = M_C_CPU1_SA_DQ<18>
  VSS75  = GND
  DQ19_A  = M_C_CPU1_SA_DQ<19>
  VSS76  = GND
  \dqs7_a_c||tdqs7_a_c\  = M_C_CPU1_SA_DQS_DN<7>
  \dqs7_a_t||tdqs7_a_t\  = M_C_CPU1_SA_DQS_DP<7>
  VSS77  = GND
  DQ22_A  = M_C_CPU1_SA_DQ<22>
  VSS78  = GND
  DQ23_A  = M_C_CPU1_SA_DQ<23>
  VSS79  = GND
  DQ26_A  = M_C_CPU1_SA_DQ<26>
  VSS80  = GND
  DQ27_A  = M_C_CPU1_SA_DQ<27>
  VSS81  = GND
  \dqs8_a_c||tdqs8_a_c\  = M_C_CPU1_SA_DQS_DN<8>
  \dqs8_a_t||tdqs8_a_t\  = M_C_CPU1_SA_DQS_DP<8>
  VSS82  = GND
  DQ30_A  = M_C_CPU1_SA_DQ<30>
  VSS83  = GND
  DQ31_A  = M_C_CPU1_SA_DQ<31>
  VSS84  = GND
  CB2_A  = M_C_CPU1_SA_CB<2>
  VSS85  = GND
  CB3_A  = M_C_CPU1_SA_CB<3>
  VSS86  = GND
  \dqs9_a_c||tdqs9_a_c\  = M_C_CPU1_SA_DQS_DN<9>
  \dqs9_a_t||tdqs9_a_t\  = M_C_CPU1_SA_DQS_DP<9>
  VSS87  = GND
  CB6_A  = M_C_CPU1_SA_CB<6>
  VSS88  = GND
  CB7_A  = M_C_CPU1_SA_CB<7>
  VSS89  = GND
  RESET_N  = RST_M_CD_CPU1_FPGA_N
  VSS90  = GND
  CS1_A_N  = M_C_CPU1_SA_CS_N<3>
  VSS91  = GND
  CA1_A  = M_C_CPU1_SA_CA<1>
  VSS92  = GND
  CA3_A  = M_C_CPU1_SA_CA<3>
  VSS93  = GND
  CA5_A  = M_C_CPU1_SA_CA<5>
  VSS94  = GND
  CK_T  = M_C_CPU1_CLK_DP<1>
  CK_C  = M_C_CPU1_CLK_DN<1>
  VSS95  = GND
  RFU4  = TP_CHC_CPU1_DIMM2_FRU_4
  CA1_B  = M_C_CPU1_SB_CA<1>
  VSS96  = GND
  CA3_B  = M_C_CPU1_SB_CA<3>
  VSS97  = GND
  CA5_B  = M_C_CPU1_SB_CA<5>
  VSS98  = GND
  PAR_B  = M_C_CPU1_SB_PAR
  VSS99  = GND
  CS1_B_N  = M_C_CPU1_SB_CS_N<3>
  VSS100  = GND
  RFU5  = TP_CHC_CPU1_DIMM2_FRU_5
  RFU6  = TP_CHC_CPU1_DIMM2_FRU_6
  VSS101  = GND
  CB6_B  = M_C_CPU1_SB_CB<6>
  VSS102  = GND
  CB7_B  = M_C_CPU1_SB_CB<7>
  VSS103  = GND
  DQS4_B_C  = M_C_CPU1_SB_DQS_DN<4>
  DQS4_B_T  = M_C_CPU1_SB_DQS_DP<4>
  VSS104  = GND
  CB2_B  = M_C_CPU1_SB_CB<2>
  VSS105  = GND
  CB3_B  = M_C_CPU1_SB_CB<3>
  VSS106  = GND
  DQ2_B  = M_C_CPU1_SB_DQ<2>
  VSS107  = GND
  DQ3_B  = M_C_CPU1_SB_DQ<3>
  VSS108  = GND
  \dqs5_b_c||tdqs5_b_c\  = M_C_CPU1_SB_DQS_DN<5>
  \dqs5_b_t||tdqs5_b_t\  = M_C_CPU1_SB_DQS_DP<5>
  VSS109  = GND
  DQ6_B  = M_C_CPU1_SB_DQ<6>
  VSS110  = GND
  DQ7_B  = M_C_CPU1_SB_DQ<7>
  VSS111  = GND
  DQ10_B  = M_C_CPU1_SB_DQ<10>
  VSS112  = GND
  DQ11_B  = M_C_CPU1_SB_DQ<11>
  VSS113  = GND
  \dqs6_b_c||tdqs6_b_c\  = M_C_CPU1_SB_DQS_DN<6>
  \dqs6_b_t||tdqs6_b_t\  = M_C_CPU1_SB_DQS_DP<6>
  VSS114  = GND
  DQ14_B  = M_C_CPU1_SB_DQ<14>
  VSS115  = GND
  DQ15_B  = M_C_CPU1_SB_DQ<15>
  VSS116  = GND
  DQ18_B  = M_C_CPU1_SB_DQ<18>
  VSS117  = GND
  DQ19_B  = M_C_CPU1_SB_DQ<19>
  VSS118  = GND
  \dqs7_b_c||tdqs7_b_c\  = M_C_CPU1_SB_DQS_DN<7>
  \dqs7_b_t||tdqs7_b_t\  = M_C_CPU1_SB_DQS_DP<7>
  VSS119  = GND
  DQ22_B  = M_C_CPU1_SB_DQ<22>
  VSS120  = GND
  DQ23_B  = M_C_CPU1_SB_DQ<23>
  VSS121  = GND
  DQ26_B  = M_C_CPU1_SB_DQ<26>
  VSS122  = GND
  DQ27_B  = M_C_CPU1_SB_DQ<27>
  VSS123  = GND
  \dqs8_b_c||tdqs8_b_c\  = M_C_CPU1_SB_DQS_DN<8>
  \dqs8_b_t||tdqs8_b_t\  = M_C_CPU1_SB_DQS_DP<8>
  VSS124  = GND
  DQ30_B  = M_C_CPU1_SB_DQ<30>
  VSS125  = GND
  DQ31_B  = M_C_CPU1_SB_DQ<31>
  VSS126  = GND
  G1  = GND
  G2  = GND
  G3  = GND

(kicad_pcb
	(version 20260206)
	(generator "pcbnew")
	(generator_version "10.0")
	(general
		(thickness 1.6)
		(legacy_teardrops no)
	)
	(paper "A4")
	(title_block
		(title "03242023_DA0F0TMBIJ0_F0T_Motherboard_J_brd_V01_OCP.brd")
		(comment 1 "Grand Teton / footprint 501 of 6105 (J22), pads 46-91 of 291")
	)
	(layers
		(0 "F.Cu" signal "TOP")
		(4 "In1.Cu" signal "GND")
		(6 "In2.Cu" signal "IN1")
		(8 "In3.Cu" signal "GND1")
		(10 "In4.Cu" signal "IN2")
		(12 "In5.Cu" signal "GND2")
		(14 "In6.Cu" signal "IN3")
		(16 "In7.Cu" signal "GND3")
		(18 "In8.Cu" signal "VCC")
		(20 "In9.Cu" signal "VCC1")
		(22 "In10.Cu" signal "GND4")
		(24 "In11.Cu" signal "IN4")
		(26 "In12.Cu" signal "GND5")
		(28 "In13.Cu" signal "IN5")
		(30 "In14.Cu" signal "GND6")
		(32 "In15.Cu" signal "IN6")
		(34 "In16.Cu" signal "GND7")
		(2 "B.Cu" signal "BOTTOM")
		(9 "F.Adhes" user "F.Adhesive")
		(11 "B.Adhes" user "B.Adhesive")
		(13 "F.Paste" user "Package Geometry/Pastemask Top")
		(15 "B.Paste" user "Package Geometry/Pastemask Bottom")
		(5 "F.SilkS" user "Ref Des/Silkscreen Top")
		(7 "B.SilkS" user "Ref Des/Silkscreen Bottom")
		(1 "F.Mask" user "Board Geometry/Soldermask Top")
		(3 "B.Mask" user "Board Geometry/Soldermask Bottom")
		(17 "Dwgs.User" user "User.Drawings")
		(19 "Cmts.User" user "User.Comments")
		(21 "Eco1.User" user "User.Eco1")
		(23 "Eco2.User" user "User.Eco2")
		(25 "Edge.Cuts" user "Board Geometry/Outline")
		(27 "Margin" user)
		(31 "F.CrtYd" user "Package Geometry/Place Bound Top")
		(29 "B.CrtYd" user "Package Geometry/Place Bound Bottom")
		(35 "F.Fab" user "Ref Des/Assembly Top")
		(33 "B.Fab" user "Ref Des/Assembly Bottom")
	)
	(footprint ""
		(layer "F.Cu")
		(at 32.82188 -258.091686)
		(property "Reference" "J22"
			(at -1.420622 -81.912714 0)
			(unlocked yes)
			(layer "F.SilkS")
			(effects
				(font
					(size 0.7874 0.5842)
					(thickness 0.1524)
				)
				(justify left)
			)
		)
		(property "Value" ""
			(at 0 0 0)
			(layer "F.Fab")
			(effects
				(font
					(size 1.27 1.27)
				)
			)
		)
		(duplicate_pad_numbers_are_jumpers no)
		(pad "46" smd rect
			(at -2.050034 -25.07488 270)
			(size 0.519938 1.4986)
			(layers "F.Cu" "F.Mask" "F.Paste")
			(net "GND")
		)
		(pad "47" smd rect
			(at -2.050034 -24.224996 270)
			(size 0.519938 1.4986)
			(layers "F.Cu" "F.Mask" "F.Paste")
			(net "M_C_CPU1_SA_DQ<28>")
		)
		(pad "48" smd rect
			(at -2.050034 -23.375112 270)
			(size 0.519938 1.4986)
			(layers "F.Cu" "F.Mask" "F.Paste")
			(net "GND")
		)
		(pad "49" smd rect
			(at -2.050034 -22.524974 270)
			(size 0.519938 1.4986)
			(layers "F.Cu" "F.Mask" "F.Paste")
			(net "M_C_CPU1_SA_DQ<29>")
		)
		(pad "50" smd rect
			(at -2.050034 -21.67509 270)
			(size 0.519938 1.4986)
			(layers "F.Cu" "F.Mask" "F.Paste")
			(net "GND")
		)
		(pad "51" smd rect
			(at -2.050034 -20.824952 270)
			(size 0.519938 1.4986)
			(layers "F.Cu" "F.Mask" "F.Paste")
			(net "M_C_CPU1_SA_CB<0>")
		)
		(pad "52" smd rect
			(at -2.050034 -19.975068 270)
			(size 0.519938 1.4986)
			(layers "F.Cu" "F.Mask" "F.Paste")
			(net "GND")
		)
		(pad "53" smd rect
			(at -2.050034 -19.12493 270)
			(size 0.519938 1.4986)
			(layers "F.Cu" "F.Mask" "F.Paste")
			(net "M_C_CPU1_SA_CB<1>")
		)
		(pad "54" smd rect
			(at -2.050034 -18.275046 270)
			(size 0.519938 1.4986)
			(layers "F.Cu" "F.Mask" "F.Paste")
			(net "GND")
		)
		(pad "55" smd rect
			(at -2.050034 -17.424908 270)
			(size 0.519938 1.4986)
			(layers "F.Cu" "F.Mask" "F.Paste")
			(net "M_C_CPU1_SA_DQS_DP<4>")
		)
		(pad "56" smd rect
			(at -2.050034 -16.575024 270)
			(size 0.519938 1.4986)
			(layers "F.Cu" "F.Mask" "F.Paste")
			(net "M_C_CPU1_SA_DQS_DN<4>")
		)
		(pad "57" smd rect
			(at -2.050034 -15.724886 270)
			(size 0.519938 1.4986)
			(layers "F.Cu" "F.Mask" "F.Paste")
			(net "GND")
		)
		(pad "58" smd rect
			(at -2.050034 -14.875002 270)
			(size 0.519938 1.4986)
			(layers "F.Cu" "F.Mask" "F.Paste")
			(net "M_C_CPU1_SA_CB<4>")
		)
		(pad "59" smd rect
			(at -2.050034 -14.025118 270)
			(size 0.519938 1.4986)
			(layers "F.Cu" "F.Mask" "F.Paste")
			(net "GND")
		)
		(pad "60" smd rect
			(at -2.050034 -13.17498 270)
			(size 0.519938 1.4986)
			(layers "F.Cu" "F.Mask" "F.Paste")
			(net "M_C_CPU1_SA_CB<5>")
		)
		(pad "61" smd rect
			(at -2.050034 -12.325096 270)
			(size 0.519938 1.4986)
			(layers "F.Cu" "F.Mask" "F.Paste")
			(net "GND")
		)
		(pad "62" smd rect
			(at -2.050034 -11.474958 270)
			(size 0.519938 1.4986)
			(layers "F.Cu" "F.Mask" "F.Paste")
			(net "M_C_CPU1_ALERT_N")
		)
		(pad "63" smd rect
			(at -2.050034 -10.625074 270)
			(size 0.519938 1.4986)
			(layers "F.Cu" "F.Mask" "F.Paste")
			(net "GND")
		)
		(pad "64" smd rect
			(at -2.050034 -9.774936 270)
			(size 0.519938 1.4986)
			(layers "F.Cu" "F.Mask" "F.Paste")
			(net "M_C_CPU1_SA_CS_N<2>")
		)
		(pad "65" smd rect
			(at -2.050034 -8.925052 270)
			(size 0.519938 1.4986)
			(layers "F.Cu" "F.Mask" "F.Paste")
			(net "GND")
		)
		(pad "66" smd rect
			(at -2.050034 -8.074914 270)
			(size 0.519938 1.4986)
			(layers "F.Cu" "F.Mask" "F.Paste")
			(net "M_C_CPU1_SA_CA<0>")
		)
		(pad "67" smd rect
			(at -2.050034 -7.22503 270)
			(size 0.519938 1.4986)
			(layers "F.Cu" "F.Mask" "F.Paste")
			(net "GND")
		)
		(pad "68" smd rect
			(at -2.050034 -6.374892 270)
			(size 0.519938 1.4986)
			(layers "F.Cu" "F.Mask" "F.Paste")
			(net "M_C_CPU1_SA_CA<2>")
		)
		(pad "69" smd rect
			(at -2.050034 -5.525008 270)
			(size 0.519938 1.4986)
			(layers "F.Cu" "F.Mask" "F.Paste")
			(net "GND")
		)
		(pad "70" smd rect
			(at -2.050034 -4.675124 270)
			(size 0.519938 1.4986)
			(layers "F.Cu" "F.Mask" "F.Paste")
			(net "M_C_CPU1_SA_CA<4>")
		)
		(pad "71" smd rect
			(at -2.050034 -3.824986 270)
			(size 0.519938 1.4986)
			(layers "F.Cu" "F.Mask" "F.Paste")
			(net "GND")
		)
		(pad "72" smd rect
			(at -2.050034 -2.975102 270)
			(size 0.519938 1.4986)
			(layers "F.Cu" "F.Mask" "F.Paste")
			(net "M_C_CPU1_SA_CA<6>")
		)
		(pad "73" smd rect
			(at -2.050034 -2.124964 270)
			(size 0.519938 1.4986)
			(layers "F.Cu" "F.Mask" "F.Paste")
			(net "GND")
		)
		(pad "74" smd rect
			(at -2.050034 -1.27508 270)
			(size 0.519938 1.4986)
			(layers "F.Cu" "F.Mask" "F.Paste")
			(net "M_C_CPU1_SA_PAR")
		)
		(pad "75" smd rect
			(at -2.050034 -0.424942 270)
			(size 0.519938 1.4986)
			(layers "F.Cu" "F.Mask" "F.Paste")
			(net "GND")
		)
		(pad "76" smd rect
			(at -2.050034 5.525008 270)
			(size 0.519938 1.4986)
			(layers "F.Cu" "F.Mask" "F.Paste")
			(net "M_C_CPU1_SB_CA<0>")
		)
		(pad "77" smd rect
			(at -2.050034 6.374892 270)
			(size 0.519938 1.4986)
			(layers "F.Cu" "F.Mask" "F.Paste")
			(net "GND")
		)
		(pad "78" smd rect
			(at -2.050034 7.22503 270)
			(size 0.519938 1.4986)
			(layers "F.Cu" "F.Mask" "F.Paste")
			(net "M_C_CPU1_SB_CA<2>")
		)
		(pad "79" smd rect
			(at -2.050034 8.074914 270)
			(size 0.519938 1.4986)
			(layers "F.Cu" "F.Mask" "F.Paste")
			(net "GND")
		)
		(pad "80" smd rect
			(at -2.050034 8.925052 270)
			(size 0.519938 1.4986)
			(layers "F.Cu" "F.Mask" "F.Paste")
			(net "M_C_CPU1_SB_CA<4>")
		)
		(pad "81" smd rect
			(at -2.050034 9.774936 270)
			(size 0.519938 1.4986)
			(layers "F.Cu" "F.Mask" "F.Paste")
			(net "GND")
		)
		(pad "82" smd rect
			(at -2.050034 10.625074 270)
			(size 0.519938 1.4986)
			(layers "F.Cu" "F.Mask" "F.Paste")
			(net "M_C_CPU1_SB_CA<6>")
		)
		(pad "83" smd rect
			(at -2.050034 11.474958 270)
			(size 0.519938 1.4986)
			(layers "F.Cu" "F.Mask" "F.Paste")
			(net "GND")
		)
		(pad "84" smd rect
			(at -2.050034 12.325096 270)
			(size 0.519938 1.4986)
			(layers "F.Cu" "F.Mask" "F.Paste")
			(net "M_C_CPU1_SB_CS_N<2>")
		)
		(pad "85" smd rect
			(at -2.050034 13.17498 270)
			(size 0.519938 1.4986)
			(layers "F.Cu" "F.Mask" "F.Paste")
			(net "GND")
		)
		(pad "86" smd rect
			(at -2.050034 14.025118 270)
			(size 0.519938 1.4986)
			(layers "F.Cu" "F.Mask" "F.Paste")
			(net "M_C_CPU1_SA_RSP<1>")
		)
		(pad "87" smd rect
			(at -2.050034 14.875002 270)
			(size 0.519938 1.4986)
			(layers "F.Cu" "F.Mask" "F.Paste")
			(net "M_C_CPU1_SB_RSP<1>")
		)
		(pad "88" smd rect
			(at -2.050034 15.724886 270)
			(size 0.519938 1.4986)
			(layers "F.Cu" "F.Mask" "F.Paste")
			(net "GND")
		)
		(pad "89" smd rect
			(at -2.050034 16.575024 270)
			(size 0.519938 1.4986)
			(layers "F.Cu" "F.Mask" "F.Paste")
			(net "M_C_CPU1_SB_CB<4>")
		)
		(pad "90" smd rect
			(at -2.050034 17.424908 270)
			(size 0.519938 1.4986)
			(layers "F.Cu" "F.Mask" "F.Paste")
			(net "GND")
		)
		(pad "91" smd rect
			(at -2.050034 18.275046 270)
			(size 0.519938 1.4986)
			(layers "F.Cu" "F.Mask" "F.Paste")
			(net "M_C_CPU1_SB_CB<5>")
		)
	)
)
